(kicad_pcb
	(version 20260206)
	(generator "pcbnew")
	(generator_version "10.0")
	(general
		(thickness 1.6)
		(legacy_teardrops no)
	)
	(paper "A4")
	(title_block
		(title "timecard-production-celestica-r4006 — R4006-B0001-02_R01.brd")
		(comment 1 "Time Appliance Project (Time Card) / footprints 906-910 of 1113")
	)
	(layers
		(0 "F.Cu" signal "TOP")
		(4 "In1.Cu" signal "L02_GND1")
		(6 "In2.Cu" signal "L03_SIG1")
		(8 "In3.Cu" signal "L04_GND2")
		(10 "In4.Cu" signal "L05_VCC1")
		(12 "In5.Cu" signal "L06_VCC2")
		(14 "In6.Cu" signal "L07_GND3")
		(16 "In7.Cu" signal "L08_SIG2")
		(18 "In8.Cu" signal "L09_GND4")
		(2 "B.Cu" signal "BOTTOM")
		(9 "F.Adhes" user "F.Adhesive")
		(11 "B.Adhes" user "B.Adhesive")
		(13 "F.Paste" user "Package Geometry/Pastemask Top")
		(15 "B.Paste" user "Package Geometry/Pastemask Bottom")
		(5 "F.SilkS" user "Ref Des/Silkscreen Top")
		(7 "B.SilkS" user "Ref Des/Silkscreen Bottom")
		(1 "F.Mask" user "Board Geometry/Soldermask Top")
		(3 "B.Mask" user "Board Geometry/Soldermask Bottom")
		(17 "Dwgs.User" user "User.Drawings")
		(19 "Cmts.User" user "User.Comments")
		(21 "Eco1.User" user "User.Eco1")
		(23 "Eco2.User" user "User.Eco2")
		(25 "Edge.Cuts" user "Board Geometry/Outline")
		(27 "Margin" user)
		(31 "F.CrtYd" user "Package Geometry/Place Bound Top")
		(29 "B.CrtYd" user "Package Geometry/Place Bound Bottom")
		(35 "F.Fab" user "Ref Des/Assembly Top")
		(33 "B.Fab" user "Ref Des/Assembly Bottom")
	)
	(footprint ""
		(layer "B.Cu")
		(at 156.718 -36.957 -90)
		(property "Reference" "R329"
			(at 5.24637 0.635 0)
			(unlocked yes)
			(layer "B.SilkS")
			(effects
				(font
					(size 0.7874 0.5842)
					(thickness 0.1524)
				)
				(justify mirror)
			)
		)
		(property "Value" "VAL*"
			(at -0.02032 2.13233 270)
			(unlocked yes)
			(layer "B.Fab")
			(hide yes)
			(effects
				(font
					(size 0.7874 0.5842)
					(thickness 0.1524)
				)
				(justify mirror)
			)
		)
		(property "Tolerance" "TOL*"
			(at -0.044704 3.05435 270)
			(unlocked yes)
			(layer "Cmts.User")
			(hide yes)
			(effects
				(font
					(size 0.7874 0.5842)
					(thickness 0.1524)
				)
				(justify mirror)
			)
		)
		(property "User Part Number" "PARTNUM*"
			(at -0.02032 4.024884 270)
			(unlocked yes)
			(layer "Cmts.User")
			(hide yes)
			(effects
				(font
					(size 0.7874 0.5842)
					(thickness 0.1524)
				)
				(justify mirror)
			)
		)
		(property "Device Type" "RESISTOR-G155-133R0-01,33OHM,1%"
			(at -0.008382 1.210564 270)
			(unlocked yes)
			(layer "B.Fab")
			(hide yes)
			(effects
				(font
					(size 0.7874 0.5842)
					(thickness 0.1524)
				)
				(justify mirror)
			)
		)
		(duplicate_pad_numbers_are_jumpers no)
		(fp_line
			(start -1.143 0.5588)
			(end -1.143 -0.5588)
			(stroke
				(width 0.1)
				(type default)
			)
			(layer "B.SilkS")
		)
		(fp_line
			(start 1.143 0.5588)
			(end -1.143 0.5588)
			(stroke
				(width 0.1)
				(type default)
			)
			(layer "B.SilkS")
		)
		(fp_line
			(start -1.143 -0.5588)
			(end 1.143 -0.5588)
			(stroke
				(width 0.1)
				(type default)
			)
			(layer "B.SilkS")
		)
		(fp_line
			(start 1.143 -0.5588)
			(end 1.143 0.5588)
			(stroke
				(width 0.1)
				(type default)
			)
			(layer "B.SilkS")
		)
		(fp_poly
			(pts
				(xy 1.143 0.5588) (xy -1.143 0.5588) (xy -1.143 -0.5588) (xy 1.143 -0.5588)
			)
			(stroke
				(width 0)
				(type default)
			)
			(fill no)
			(layer "B.CrtYd")
		)
		(fp_line
			(start -0.508 0.3048)
			(end -0.508 -0.3048)
			(stroke
				(width 0.1)
				(type default)
			)
			(layer "B.Fab")
		)
		(fp_line
			(start 0.508 0.3048)
			(end -0.508 0.3048)
			(stroke
				(width 0.1)
				(type default)
			)
			(layer "B.Fab")
		)
		(fp_line
			(start -0.508 -0.3048)
			(end 0.508 -0.3048)
			(stroke
				(width 0.1)
				(type default)
			)
			(layer "B.Fab")
		)
		(fp_line
			(start 0.508 -0.3048)
			(end 0.508 0.3048)
			(stroke
				(width 0.1)
				(type default)
			)
			(layer "B.Fab")
		)
		(pad "1" smd rect
			(at 0.5334 0 90)
			(size 0.7112 0.6096)
			(layers "B.Cu" "B.Mask" "B.Paste")
			(net "FPGA_IO_7")
		)
		(pad "2" smd rect
			(at -0.5334 0 90)
			(size 0.7112 0.6096)
			(layers "B.Cu" "B.Mask" "B.Paste")
			(net "UNNAMED_16_CONNHDR2X6FSSMT_I1_4")
		)
		(zone
			(layer "B.Cu")
			(hatch none 0.5)
			(connect_pads
				(clearance 0)
			)
			(min_thickness 0.25)
			(keepout
				(tracks not_allowed)
				(vias allowed)
				(pads allowed)
				(copperpour not_allowed)
				(footprints allowed)
			)
			(placement
				(enabled no)
				(sheetname "")
			)
			(fill
				(thermal_gap 0.5)
				(thermal_bridge_width 0.5)
				(island_removal_mode 0)
			)
			(polygon
				(pts
					(xy 156.4132 -36.8808) (xy 157.0228 -36.8808) (xy 157.0228 -37.0332) (xy 156.4132 -37.0332)
				)
			)
		)
		(zone
			(layer "B.Cu")
			(hatch none 0.5)
			(connect_pads
				(clearance 0)
			)
			(min_thickness 0.25)
			(keepout
				(tracks allowed)
				(vias not_allowed)
				(pads allowed)
				(copperpour not_allowed)
				(footprints allowed)
			)
			(placement
				(enabled no)
				(sheetname "")
			)
			(fill
				(thermal_gap 0.5)
				(thermal_bridge_width 0.5)
				(island_removal_mode 0)
			)
			(polygon
				(pts
					(xy 156.4132 -36.8808) (xy 157.0228 -36.8808) (xy 157.0228 -37.0332) (xy 156.4132 -37.0332)
				)
			)
		)
	)
	(footprint ""
		(layer "B.Cu")
		(at 80.899 -99.06 90)
		(property "Reference" "C57"
			(at 0.127 -1.43637 270)
			(unlocked yes)
			(layer "B.SilkS")
			(effects
				(font
					(size 0.7874 0.5842)
					(thickness 0.1524)
				)
				(justify mirror)
			)
		)
		(property "Value" "VAL*"
			(at -0.0762 2.067306 90)
			(unlocked yes)
			(layer "B.Fab")
			(hide yes)
			(effects
				(font
					(size 0.7874 0.5842)
					(thickness 0.1524)
				)
				(justify mirror)
			)
		)
		(property "Tolerance" "TOL*"
			(at -0.0762 3.032506 90)
			(unlocked yes)
			(layer "Cmts.User")
			(hide yes)
			(effects
				(font
					(size 0.7874 0.5842)
					(thickness 0.1524)
				)
				(justify mirror)
			)
		)
		(property "User Part Number" "PARTNUM*"
			(at -0.1016 4.023106 90)
			(unlocked yes)
			(layer "Cmts.User")
			(hide yes)
			(effects
				(font
					(size 0.7874 0.5842)
					(thickness 0.1524)
				)
				(justify mirror)
			)
		)
		(property "Device Type" "CAPACITOR-G105-0A102-FJ,1000PFA"
			(at -0.0508 1.127506 90)
			(unlocked yes)
			(layer "B.Fab")
			(hide yes)
			(effects
				(font
					(size 0.7874 0.5842)
					(thickness 0.1524)
				)
				(justify mirror)
			)
		)
		(duplicate_pad_numbers_are_jumpers no)
		(fp_line
			(start 1.143 -0.5588)
			(end 1.143 0.5588)
			(stroke
				(width 0.1)
				(type default)
			)
			(layer "B.SilkS")
		)
		(fp_line
			(start -1.143 -0.5588)
			(end 1.143 -0.5588)
			(stroke
				(width 0.1)
				(type default)
			)
			(layer "B.SilkS")
		)
		(fp_line
			(start 1.143 0.5588)
			(end -1.143 0.5588)
			(stroke
				(width 0.1)
				(type default)
			)
			(layer "B.SilkS")
		)
		(fp_line
			(start -1.143 0.5588)
			(end -1.143 -0.5588)
			(stroke
				(width 0.1)
				(type default)
			)
			(layer "B.SilkS")
		)
		(fp_rect
			(start -1.143 -0.5588)
			(end 1.143 0.5588)
			(stroke
				(width 0)
				(type default)
			)
			(fill no)
			(layer "B.CrtYd")
		)
		(fp_line
			(start 0.508 -0.3048)
			(end 0.508 0.3048)
			(stroke
				(width 0.1)
				(type default)
			)
			(layer "B.Fab")
		)
		(fp_line
			(start -0.508 -0.3048)
			(end 0.508 -0.3048)
			(stroke
				(width 0.1)
				(type default)
			)
			(layer "B.Fab")
		)
		(fp_line
			(start 0.508 0.3048)
			(end -0.508 0.3048)
			(stroke
				(width 0.1)
				(type default)
			)
			(layer "B.Fab")
		)
		(fp_line
			(start -0.508 0.3048)
			(end -0.508 -0.3048)
			(stroke
				(width 0.1)
				(type default)
			)
			(layer "B.Fab")
		)
		(pad "1" smd rect
			(at 0.5334 0 270)
			(size 0.7112 0.6096)
			(layers "B.Cu" "B.Mask" "B.Paste")
			(net "XP3R3V_SW")
		)
		(pad "2" smd rect
			(at -0.5334 0 270)
			(size 0.7112 0.6096)
			(layers "B.Cu" "B.Mask" "B.Paste")
			(net "UNNAMED_517_CAPACITOR_I29_2")
		)
		(zone
			(layer "B.Cu")
			(hatch none 0.5)
			(connect_pads
				(clearance 0)
			)
			(min_thickness 0.25)
			(keepout
				(tracks allowed)
				(vias not_allowed)
				(pads allowed)
				(copperpour not_allowed)
				(footprints allowed)
			)
			(placement
				(enabled no)
				(sheetname "")
			)
			(fill
				(thermal_gap 0.5)
				(thermal_bridge_width 0.5)
				(island_removal_mode 0)
			)
			(polygon
				(pts
					(xy 80.5942 -98.9838) (xy 81.2038 -98.9838) (xy 81.2038 -99.1362) (xy 80.5942 -99.1362)
				)
			)
		)
	)
	(footprint ""
		(layer "B.Cu")
		(at 70.866 -55.499 -90)
		(property "Reference" "C71"
			(at 2.159 -0.21463 270)
			(unlocked yes)
			(layer "B.SilkS")
			(effects
				(font
					(size 0.7874 0.5842)
					(thickness 0.1524)
				)
				(justify mirror)
			)
		)
		(property "Value" "VAL*"
			(at -0.0762 2.067306 270)
			(unlocked yes)
			(layer "B.Fab")
			(hide yes)
			(effects
				(font
					(size 0.7874 0.5842)
					(thickness 0.1524)
				)
				(justify mirror)
			)
		)
		(property "Device Type" "CAPACITOR-G105-0B104-EK,0.1UF,A"
			(at -0.0508 1.127506 270)
			(unlocked yes)
			(layer "B.Fab")
			(hide yes)
			(effects
				(font
					(size 0.7874 0.5842)
					(thickness 0.1524)
				)
				(justify mirror)
			)
		)
		(property "User Part Number" "PARTNUM*"
			(at -0.1016 4.023106 270)
			(unlocked yes)
			(layer "Cmts.User")
			(hide yes)
			(effects
				(font
					(size 0.7874 0.5842)
					(thickness 0.1524)
				)
				(justify mirror)
			)
		)
		(property "Tolerance" "TOL*"
			(at -0.0762 3.032506 270)
			(unlocked yes)
			(layer "Cmts.User")
			(hide yes)
			(effects
				(font
					(size 0.7874 0.5842)
					(thickness 0.1524)
				)
				(justify mirror)
			)
		)
		(duplicate_pad_numbers_are_jumpers no)
		(fp_line
			(start -1.143 0.5588)
			(end -1.143 -0.5588)
			(stroke
				(width 0.1)
				(type default)
			)
			(layer "B.SilkS")
		)
		(fp_line
			(start 1.143 0.5588)
			(end -1.143 0.5588)
			(stroke
				(width 0.1)
				(type default)
			)
			(layer "B.SilkS")
		)
		(fp_line
			(start -1.143 -0.5588)
			(end 1.143 -0.5588)
			(stroke
				(width 0.1)
				(type default)
			)
			(layer "B.SilkS")
		)
		(fp_line
			(start 1.143 -0.5588)
			(end 1.143 0.5588)
			(stroke
				(width 0.1)
				(type default)
			)
			(layer "B.SilkS")
		)
		(fp_rect
			(start 1.143 0.5588)
			(end -1.143 -0.5588)
			(stroke
				(width 0)
				(type default)
			)
			(fill no)
			(layer "B.CrtYd")
		)
		(fp_line
			(start -0.508 0.3048)
			(end -0.508 -0.3048)
			(stroke
				(width 0.1)
				(type default)
			)
			(layer "B.Fab")
		)
		(fp_line
			(start 0.508 0.3048)
			(end -0.508 0.3048)
			(stroke
				(width 0.1)
				(type default)
			)
			(layer "B.Fab")
		)
		(fp_line
			(start -0.508 -0.3048)
			(end 0.508 -0.3048)
			(stroke
				(width 0.1)
				(type default)
			)
			(layer "B.Fab")
		)
		(fp_line
			(start 0.508 -0.3048)
			(end 0.508 0.3048)
			(stroke
				(width 0.1)
				(type default)
			)
			(layer "B.Fab")
		)
		(pad "1" smd rect
			(at 0.5334 0 90)
			(size 0.7112 0.6096)
			(layers "B.Cu" "B.Mask" "B.Paste")
			(net "XP5R0V_MAC_USB")
		)
		(pad "2" smd rect
			(at -0.5334 0 90)
			(size 0.7112 0.6096)
			(layers "B.Cu" "B.Mask" "B.Paste")
			(net "SG")
		)
		(zone
			(layer "B.Cu")
			(hatch none 0.5)
			(connect_pads
				(clearance 0)
			)
			(min_thickness 0.25)
			(keepout
				(tracks allowed)
				(vias not_allowed)
				(pads allowed)
				(copperpour not_allowed)
				(footprints allowed)
			)
			(placement
				(enabled no)
				(sheetname "")
			)
			(fill
				(thermal_gap 0.5)
				(thermal_bridge_width 0.5)
				(island_removal_mode 0)
			)
			(polygon
				(pts
					(xy 70.5612 -55.4228) (xy 71.1708 -55.4228) (xy 71.1708 -55.5752) (xy 70.5612 -55.5752)
				)
			)
		)
	)
	(footprint ""
		(layer "B.Cu")
		(at 102.489 -59.055)
		(property "Reference" "C172"
			(at -0.254 -2.11963 0)
			(unlocked yes)
			(layer "B.SilkS")
			(effects
				(font
					(size 0.7874 0.5842)
					(thickness 0.1524)
				)
				(justify mirror)
			)
		)
		(property "Value" "VAL*"
			(at -0.1016 3.769106 0)
			(unlocked yes)
			(layer "B.Fab")
			(hide yes)
			(effects
				(font
					(size 0.7874 0.5842)
					(thickness 0.1524)
				)
				(justify mirror)
			)
		)
		(property "Device Type" "CAPACITOR-G109-0G107-BM,100UF,A"
			(at -0.0762 2.829306 0)
			(unlocked yes)
			(layer "B.Fab")
			(hide yes)
			(effects
				(font
					(size 0.7874 0.5842)
					(thickness 0.1524)
				)
				(justify mirror)
			)
		)
		(property "User Part Number" "PARTNUM*"
			(at -0.2032 5.801106 0)
			(unlocked yes)
			(layer "Cmts.User")
			(hide yes)
			(effects
				(font
					(size 0.7874 0.5842)
					(thickness 0.1524)
				)
				(justify mirror)
			)
		)
		(property "Tolerance" "TOL*"
			(at -0.127 4.734306 0)
			(unlocked yes)
			(layer "Cmts.User")
			(hide yes)
			(effects
				(font
					(size 0.7874 0.5842)
					(thickness 0.1524)
				)
				(justify mirror)
			)
		)
		(duplicate_pad_numbers_are_jumpers no)
		(fp_line
			(start -2.159 -1.5748)
			(end -2.159 1.5748)
			(stroke
				(width 0.1)
				(type default)
			)
			(layer "B.SilkS")
		)
		(fp_line
			(start -2.159 1.5748)
			(end 2.159 1.5748)
			(stroke
				(width 0.1)
				(type default)
			)
			(layer "B.SilkS")
		)
		(fp_line
			(start 2.159 -1.5748)
			(end -2.159 -1.5748)
			(stroke
				(width 0.1)
				(type default)
			)
			(layer "B.SilkS")
		)
		(fp_line
			(start 2.159 1.5748)
			(end 2.159 -1.5748)
			(stroke
				(width 0.1)
				(type default)
			)
			(layer "B.SilkS")
		)
		(fp_rect
			(start 2.159 -1.5748)
			(end -2.159 1.5748)
			(stroke
				(width 0)
				(type default)
			)
			(fill no)
			(layer "B.CrtYd")
		)
		(fp_line
			(start -1.6002 -1.2446)
			(end 1.6002 -1.2446)
			(stroke
				(width 0.1)
				(type default)
			)
			(layer "B.Fab")
		)
		(fp_line
			(start -1.6002 1.2446)
			(end -1.6002 -1.2446)
			(stroke
				(width 0.1)
				(type default)
			)
			(layer "B.Fab")
		)
		(fp_line
			(start 1.6002 -1.2446)
			(end 1.6002 1.2446)
			(stroke
				(width 0.1)
				(type default)
			)
			(layer "B.Fab")
		)
		(fp_line
			(start 1.6002 1.2446)
			(end -1.6002 1.2446)
			(stroke
				(width 0.1)
				(type default)
			)
			(layer "B.Fab")
		)
		(pad "1" smd rect
			(at 1.3335 0 180)
			(size 1.143 2.6416)
			(layers "B.Cu" "B.Mask" "B.Paste")
			(net "XP3R3V_FPGA")
		)
		(pad "2" smd rect
			(at -1.3335 0 180)
			(size 1.143 2.6416)
			(layers "B.Cu" "B.Mask" "B.Paste")
			(net "SG")
		)
		(zone
			(layer "B.Cu")
			(hatch none 0.5)
			(connect_pads
				(clearance 0)
			)
			(min_thickness 0.25)
			(keepout
				(tracks allowed)
				(vias not_allowed)
				(pads allowed)
				(copperpour not_allowed)
				(footprints allowed)
			)
			(placement
				(enabled no)
				(sheetname "")
			)
			(fill
				(thermal_gap 0.5)
				(thermal_bridge_width 0.5)
				(island_removal_mode 0)
			)
			(polygon
				(pts
					(xy 103.1748 -60.452) (xy 101.8032 -60.452) (xy 101.8032 -57.658) (xy 103.1748 -57.658)
				)
			)
		)
	)
	(footprint ""
		(layer "B.Cu")
		(at 45.72 -102.743 -90)
		(property "Reference" "C45"
			(at 0.1524 -1.38303 270)
			(unlocked yes)
			(layer "B.SilkS")
			(effects
				(font
					(size 0.7874 0.5842)
					(thickness 0.1524)
				)
				(justify mirror)
			)
		)
		(property "Value" "VAL*"
			(at -0.0762 2.067306 270)
			(unlocked yes)
			(layer "B.Fab")
			(hide yes)
			(effects
				(font
					(size 0.7874 0.5842)
					(thickness 0.1524)
				)
				(justify mirror)
			)
		)
		(property "Tolerance" "TOL*"
			(at -0.0762 3.032506 270)
			(unlocked yes)
			(layer "Cmts.User")
			(hide yes)
			(effects
				(font
					(size 0.7874 0.5842)
					(thickness 0.1524)
				)
				(justify mirror)
			)
		)
		(property "User Part Number" "PARTNUM*"
			(at -0.1016 4.023106 270)
			(unlocked yes)
			(layer "Cmts.User")
			(hide yes)
			(effects
				(font
					(size 0.7874 0.5842)
					(thickness 0.1524)
				)
				(justify mirror)
			)
		)
		(property "Device Type" "CAPACITOR-G105-0A102-FJ,1000PFA"
			(at -0.0508 1.127506 270)
			(unlocked yes)
			(layer "B.Fab")
			(hide yes)
			(effects
				(font
					(size 0.7874 0.5842)
					(thickness 0.1524)
				)
				(justify mirror)
			)
		)
		(duplicate_pad_numbers_are_jumpers no)
		(fp_line
			(start -1.143 0.5588)
			(end -1.143 -0.5588)
			(stroke
				(width 0.1)
				(type default)
			)
			(layer "B.SilkS")
		)
		(fp_line
			(start 1.143 0.5588)
			(end -1.143 0.5588)
			(stroke
				(width 0.1)
				(type default)
			)
			(layer "B.SilkS")
		)
		(fp_line
			(start -1.143 -0.5588)
			(end 1.143 -0.5588)
			(stroke
				(width 0.1)
				(type default)
			)
			(layer "B.SilkS")
		)
		(fp_line
			(start 1.143 -0.5588)
			(end 1.143 0.5588)
			(stroke
				(width 0.1)
				(type default)
			)
			(layer "B.SilkS")
		)
		(fp_rect
			(start -1.143 -0.5588)
			(end 1.143 0.5588)
			(stroke
				(width 0)
				(type default)
			)
			(fill no)
			(layer "B.CrtYd")
		)
		(fp_line
			(start -0.508 0.3048)
			(end -0.508 -0.3048)
			(stroke
				(width 0.1)
				(type default)
			)
			(layer "B.Fab")
		)
		(fp_line
			(start 0.508 0.3048)
			(end -0.508 0.3048)
			(stroke
				(width 0.1)
				(type default)
			)
			(layer "B.Fab")
		)
		(fp_line
			(start -0.508 -0.3048)
			(end 0.508 -0.3048)
			(stroke
				(width 0.1)
				(type default)
			)
			(layer "B.Fab")
		)
		(fp_line
			(start 0.508 -0.3048)
			(end 0.508 0.3048)
			(stroke
				(width 0.1)
				(type default)
			)
			(layer "B.Fab")
		)
		(pad "1" smd rect
			(at 0.5334 0 90)
			(size 0.7112 0.6096)
			(layers "B.Cu" "B.Mask" "B.Paste")
			(net "XP5R0V_SW")
		)
		(pad "2" smd rect
			(at -0.5334 0 90)
			(size 0.7112 0.6096)
			(layers "B.Cu" "B.Mask" "B.Paste")
			(net "UNNAMED_516_CAPACITOR_I37_2")
		)
		(zone
			(layer "B.Cu")
			(hatch none 0.5)
			(connect_pads
				(clearance 0)
			)
			(min_thickness 0.25)
			(keepout
				(tracks allowed)
				(vias not_allowed)
				(pads allowed)
				(copperpour not_allowed)
				(footprints allowed)
			)
			(placement
				(enabled no)
				(sheetname "")
			)
			(fill
				(thermal_gap 0.5)
				(thermal_bridge_width 0.5)
				(island_removal_mode 0)
			)
			(polygon
				(pts
					(xy 46.0248 -102.8192) (xy 45.4152 -102.8192) (xy 45.4152 -102.6668) (xy 46.0248 -102.6668)
				)
			)
		)
	)
)
